(kicad_pcb
	(version 20260206)
	(generator "pcbnew")
	(generator_version "10.0")
	(general
		(thickness 1.6)
		(legacy_teardrops no)
	)
	(paper "A4")
	(title_block
		(title "03242023_DA0F0TMBIJ0_F0T_Motherboard_J_brd_V01_OCP.brd")
		(comment 1 "Grand Teton / footprints 4270-4275 of 6105")
	)
	(layers
		(0 "F.Cu" signal "TOP")
		(4 "In1.Cu" signal "GND")
		(6 "In2.Cu" signal "IN1")
		(8 "In3.Cu" signal "GND1")
		(10 "In4.Cu" signal "IN2")
		(12 "In5.Cu" signal "GND2")
		(14 "In6.Cu" signal "IN3")
		(16 "In7.Cu" signal "GND3")
		(18 "In8.Cu" signal "VCC")
		(20 "In9.Cu" signal "VCC1")
		(22 "In10.Cu" signal "GND4")
		(24 "In11.Cu" signal "IN4")
		(26 "In12.Cu" signal "GND5")
		(28 "In13.Cu" signal "IN5")
		(30 "In14.Cu" signal "GND6")
		(32 "In15.Cu" signal "IN6")
		(34 "In16.Cu" signal "GND7")
		(2 "B.Cu" signal "BOTTOM")
		(9 "F.Adhes" user "F.Adhesive")
		(11 "B.Adhes" user "B.Adhesive")
		(13 "F.Paste" user "Package Geometry/Pastemask Top")
		(15 "B.Paste" user "Package Geometry/Pastemask Bottom")
		(5 "F.SilkS" user "Ref Des/Silkscreen Top")
		(7 "B.SilkS" user "Ref Des/Silkscreen Bottom")
		(1 "F.Mask" user "Board Geometry/Soldermask Top")
		(3 "B.Mask" user "Board Geometry/Soldermask Bottom")
		(17 "Dwgs.User" user "User.Drawings")
		(19 "Cmts.User" user "User.Comments")
		(21 "Eco1.User" user "User.Eco1")
		(23 "Eco2.User" user "User.Eco2")
		(25 "Edge.Cuts" user "Board Geometry/Outline")
		(27 "Margin" user)
		(31 "F.CrtYd" user "Package Geometry/Place Bound Top")
		(29 "B.CrtYd" user "Package Geometry/Place Bound Bottom")
		(35 "F.Fab" user "Ref Des/Assembly Top")
		(33 "B.Fab" user "Ref Des/Assembly Bottom")
	)
	(footprint ""
		(layer "B.Cu")
		(at 160.83788 -117.566948)
		(property "Reference" "R920"
			(at 0 0 0)
			(layer "B.SilkS")
			(hide yes)
			(effects
				(font
					(size 1.27 1.27)
				)
				(justify mirror)
			)
		)
		(property "Value" ""
			(at 0 0 0)
			(layer "B.Fab")
			(effects
				(font
					(size 1.27 1.27)
				)
				(justify mirror)
			)
		)
		(duplicate_pad_numbers_are_jumpers no)
		(fp_line
			(start -0.7874 -0.4064)
			(end -0.7874 0.4064)
			(stroke
				(width 0.1524)
				(type default)
			)
			(layer "B.SilkS")
		)
		(fp_line
			(start -0.7874 0.4064)
			(end 0.7874 0.4064)
			(stroke
				(width 0.1524)
				(type default)
			)
			(layer "B.SilkS")
		)
		(fp_line
			(start 0.7874 -0.4064)
			(end -0.7874 -0.4064)
			(stroke
				(width 0.1524)
				(type default)
			)
			(layer "B.SilkS")
		)
		(fp_line
			(start 0.7874 0.4064)
			(end 0.7874 -0.4064)
			(stroke
				(width 0.1524)
				(type default)
			)
			(layer "B.SilkS")
		)
		(fp_line
			(start -0.67945 -0.3048)
			(end -0.67945 0.3048)
			(stroke
				(width 0.1)
				(type default)
			)
			(layer "B.Fab")
		)
		(fp_line
			(start -0.67945 0.3048)
			(end -0.120396 0.3048)
			(stroke
				(width 0.1)
				(type default)
			)
			(layer "B.Fab")
		)
		(fp_line
			(start -0.12065 -0.3048)
			(end -0.67945 -0.3048)
			(stroke
				(width 0.1)
				(type default)
			)
			(layer "B.Fab")
		)
		(fp_line
			(start -0.12065 -0.2794)
			(end -0.12065 -0.3048)
			(stroke
				(width 0.1)
				(type default)
			)
			(layer "B.Fab")
		)
		(fp_line
			(start -0.120396 0.2794)
			(end 0.12065 0.2794)
			(stroke
				(width 0.1)
				(type default)
			)
			(layer "B.Fab")
		)
		(fp_line
			(start -0.120396 0.3048)
			(end -0.120396 0.2794)
			(stroke
				(width 0.1)
				(type default)
			)
			(layer "B.Fab")
		)
		(fp_line
			(start 0.12065 -0.305054)
			(end 0.12065 -0.2794)
			(stroke
				(width 0.1)
				(type default)
			)
			(layer "B.Fab")
		)
		(fp_line
			(start 0.12065 -0.2794)
			(end -0.12065 -0.2794)
			(stroke
				(width 0.1)
				(type default)
			)
			(layer "B.Fab")
		)
		(fp_line
			(start 0.12065 0.2794)
			(end 0.12065 0.3048)
			(stroke
				(width 0.1)
				(type default)
			)
			(layer "B.Fab")
		)
		(fp_line
			(start 0.12065 0.3048)
			(end 0.67945 0.3048)
			(stroke
				(width 0.1)
				(type default)
			)
			(layer "B.Fab")
		)
		(fp_line
			(start 0.67945 -0.305054)
			(end 0.12065 -0.305054)
			(stroke
				(width 0.1)
				(type default)
			)
			(layer "B.Fab")
		)
		(fp_line
			(start 0.67945 0.3048)
			(end 0.67945 -0.305054)
			(stroke
				(width 0.1)
				(type default)
			)
			(layer "B.Fab")
		)
		(pad "1" smd circle
			(at 0.40005 0 180)
			(size 0 0)
			(layers "B.Cu" "B.Mask" "B.Paste")
			(net "JTAG_PLD_JTAGEN")
		)
		(pad "2" smd circle
			(at -0.40005 0 180)
			(size 0 0)
			(layers "B.Cu" "B.Mask" "B.Paste")
			(net "GND")
		)
	)
	(footprint ""
		(layer "B.Cu")
		(at 129.545588 -329.921616 -90)
		(property "Reference" "PC587"
			(at 0 0 90)
			(layer "B.SilkS")
			(hide yes)
			(effects
				(font
					(size 1.27 1.27)
				)
				(justify mirror)
			)
		)
		(property "Value" ""
			(at 0 0 90)
			(layer "B.Fab")
			(effects
				(font
					(size 1.27 1.27)
				)
				(justify mirror)
			)
		)
		(duplicate_pad_numbers_are_jumpers no)
		(fp_line
			(start -4.533392 2.249932)
			(end 4.533392 2.249932)
			(stroke
				(width 0.1524)
				(type default)
			)
			(layer "B.SilkS")
		)
		(fp_line
			(start 4.533392 2.249932)
			(end 4.533392 -2.249932)
			(stroke
				(width 0.1524)
				(type default)
			)
			(layer "B.SilkS")
		)
		(fp_line
			(start -4.533392 -2.249932)
			(end -4.533392 2.249932)
			(stroke
				(width 0.1524)
				(type default)
			)
			(layer "B.SilkS")
		)
		(fp_line
			(start 4.533392 -2.249932)
			(end -4.533392 -2.249932)
			(stroke
				(width 0.1524)
				(type default)
			)
			(layer "B.SilkS")
		)
		(fp_rect
			(start 5.39242 2.326132)
			(end 4.533392 -2.326132)
			(stroke
				(width 0)
				(type default)
			)
			(fill yes)
			(layer "B.SilkS")
		)
		(fp_line
			(start -3.750056 2.249932)
			(end 3.750056 2.249932)
			(stroke
				(width 0.1)
				(type default)
			)
			(layer "B.Fab")
		)
		(fp_line
			(start 3.750056 2.249932)
			(end 3.750056 -2.249932)
			(stroke
				(width 0.1)
				(type default)
			)
			(layer "B.Fab")
		)
		(fp_line
			(start -3.750056 -2.249932)
			(end -3.750056 2.249932)
			(stroke
				(width 0.1)
				(type default)
			)
			(layer "B.Fab")
		)
		(fp_line
			(start 3.750056 -2.249932)
			(end -3.750056 -2.249932)
			(stroke
				(width 0.1)
				(type default)
			)
			(layer "B.Fab")
		)
		(fp_text user "-"
			(at -4.507992 1.355598 270)
			(unlocked yes)
			(layer "B.SilkS")
			(effects
				(font
					(size 1.905 1.4224)
					(thickness 0.1524)
				)
				(justify left mirror)
			)
		)
		(fp_text user "+"
			(at 6.322314 0.786384 180)
			(unlocked yes)
			(layer "B.SilkS")
			(effects
				(font
					(size 1.905 1.4224)
					(thickness 0.1524)
				)
				(justify left mirror)
			)
		)
		(fp_text user "+"
			(at 6.322314 0.786384 180)
			(unlocked yes)
			(layer "B.Fab")
			(effects
				(font
					(size 1.905 1.4224)
					(thickness 0.1524)
				)
				(justify left mirror)
			)
		)
		(fp_text user "-"
			(at -4.8514 -0.14605 270)
			(unlocked yes)
			(layer "B.Fab")
			(effects
				(font
					(size 1.905 1.4224)
					(thickness 0.1524)
				)
				(justify left mirror)
			)
		)
		(pad "1" smd rect
			(at 3.199892 0 90)
			(size 2.413 2.8194)
			(layers "B.Cu" "B.Mask" "B.Paste")
			(net "PVCCIN_CPU1")
		)
		(pad "2" smd rect
			(at -3.199892 0 90)
			(size 2.413 2.8194)
			(layers "B.Cu" "B.Mask" "B.Paste")
			(net "GND")
		)
	)
	(footprint ""
		(layer "B.Cu")
		(at 286.2834 -363.79277 -90)
		(property "Reference" "PR1300"
			(at 0 0 90)
			(layer "B.SilkS")
			(hide yes)
			(effects
				(font
					(size 1.27 1.27)
				)
				(justify mirror)
			)
		)
		(property "Value" ""
			(at 0 0 90)
			(layer "B.Fab")
			(effects
				(font
					(size 1.27 1.27)
				)
				(justify mirror)
			)
		)
		(duplicate_pad_numbers_are_jumpers no)
		(fp_line
			(start -0.7874 0.4064)
			(end 0.7874 0.4064)
			(stroke
				(width 0.1524)
				(type default)
			)
			(layer "B.SilkS")
		)
		(fp_line
			(start 0.7874 0.4064)
			(end 0.7874 -0.4064)
			(stroke
				(width 0.1524)
				(type default)
			)
			(layer "B.SilkS")
		)
		(fp_line
			(start -0.7874 -0.4064)
			(end -0.7874 0.4064)
			(stroke
				(width 0.1524)
				(type default)
			)
			(layer "B.SilkS")
		)
		(fp_line
			(start 0.7874 -0.4064)
			(end -0.7874 -0.4064)
			(stroke
				(width 0.1524)
				(type default)
			)
			(layer "B.SilkS")
		)
		(fp_line
			(start -0.67945 0.3048)
			(end -0.120396 0.3048)
			(stroke
				(width 0.1)
				(type default)
			)
			(layer "B.Fab")
		)
		(fp_line
			(start -0.120396 0.3048)
			(end -0.120396 0.2794)
			(stroke
				(width 0.1)
				(type default)
			)
			(layer "B.Fab")
		)
		(fp_line
			(start 0.12065 0.3048)
			(end 0.67945 0.3048)
			(stroke
				(width 0.1)
				(type default)
			)
			(layer "B.Fab")
		)
		(fp_line
			(start 0.67945 0.3048)
			(end 0.67945 -0.305054)
			(stroke
				(width 0.1)
				(type default)
			)
			(layer "B.Fab")
		)
		(fp_line
			(start -0.120396 0.2794)
			(end 0.12065 0.2794)
			(stroke
				(width 0.1)
				(type default)
			)
			(layer "B.Fab")
		)
		(fp_line
			(start 0.12065 0.2794)
			(end 0.12065 0.3048)
			(stroke
				(width 0.1)
				(type default)
			)
			(layer "B.Fab")
		)
		(fp_line
			(start -0.12065 -0.2794)
			(end -0.12065 -0.3048)
			(stroke
				(width 0.1)
				(type default)
			)
			(layer "B.Fab")
		)
		(fp_line
			(start 0.12065 -0.2794)
			(end -0.12065 -0.2794)
			(stroke
				(width 0.1)
				(type default)
			)
			(layer "B.Fab")
		)
		(fp_line
			(start -0.67945 -0.3048)
			(end -0.67945 0.3048)
			(stroke
				(width 0.1)
				(type default)
			)
			(layer "B.Fab")
		)
		(fp_line
			(start -0.12065 -0.3048)
			(end -0.67945 -0.3048)
			(stroke
				(width 0.1)
				(type default)
			)
			(layer "B.Fab")
		)
		(fp_line
			(start 0.12065 -0.305054)
			(end 0.12065 -0.2794)
			(stroke
				(width 0.1)
				(type default)
			)
			(layer "B.Fab")
		)
		(fp_line
			(start 0.67945 -0.305054)
			(end 0.12065 -0.305054)
			(stroke
				(width 0.1)
				(type default)
			)
			(layer "B.Fab")
		)
		(pad "1" smd circle
			(at 0.40005 0 90)
			(size 0 0)
			(layers "B.Cu" "B.Mask" "B.Paste")
			(net "PVCCFA_EHV_FIVRA_CPU0_PVCC2")
		)
		(pad "2" smd circle
			(at -0.40005 0 90)
			(size 0 0)
			(layers "B.Cu" "B.Mask" "B.Paste")
			(net "PVCCFA_EHV_FIVRA_CPU0_VDD4")
		)
	)
	(footprint ""
		(layer "B.Cu")
		(at 73.84288 -11.267948 -90)
		(property "Reference" "R3162"
			(at 0 0 90)
			(layer "B.SilkS")
			(hide yes)
			(effects
				(font
					(size 1.27 1.27)
				)
				(justify mirror)
			)
		)
		(property "Value" ""
			(at 0 0 90)
			(layer "B.Fab")
			(effects
				(font
					(size 1.27 1.27)
				)
				(justify mirror)
			)
		)
		(duplicate_pad_numbers_are_jumpers no)
		(fp_line
			(start -0.7874 0.4064)
			(end 0.7874 0.4064)
			(stroke
				(width 0.1524)
				(type default)
			)
			(layer "B.SilkS")
		)
		(fp_line
			(start 0.7874 0.4064)
			(end 0.7874 -0.4064)
			(stroke
				(width 0.1524)
				(type default)
			)
			(layer "B.SilkS")
		)
		(fp_line
			(start -0.7874 -0.4064)
			(end -0.7874 0.4064)
			(stroke
				(width 0.1524)
				(type default)
			)
			(layer "B.SilkS")
		)
		(fp_line
			(start 0.7874 -0.4064)
			(end -0.7874 -0.4064)
			(stroke
				(width 0.1524)
				(type default)
			)
			(layer "B.SilkS")
		)
		(fp_line
			(start -0.67945 0.3048)
			(end -0.120396 0.3048)
			(stroke
				(width 0.1)
				(type default)
			)
			(layer "B.Fab")
		)
		(fp_line
			(start -0.120396 0.3048)
			(end -0.120396 0.2794)
			(stroke
				(width 0.1)
				(type default)
			)
			(layer "B.Fab")
		)
		(fp_line
			(start 0.12065 0.3048)
			(end 0.67945 0.3048)
			(stroke
				(width 0.1)
				(type default)
			)
			(layer "B.Fab")
		)
		(fp_line
			(start 0.67945 0.3048)
			(end 0.67945 -0.305054)
			(stroke
				(width 0.1)
				(type default)
			)
			(layer "B.Fab")
		)
		(fp_line
			(start -0.120396 0.2794)
			(end 0.12065 0.2794)
			(stroke
				(width 0.1)
				(type default)
			)
			(layer "B.Fab")
		)
		(fp_line
			(start 0.12065 0.2794)
			(end 0.12065 0.3048)
			(stroke
				(width 0.1)
				(type default)
			)
			(layer "B.Fab")
		)
		(fp_line
			(start -0.12065 -0.2794)
			(end -0.12065 -0.3048)
			(stroke
				(width 0.1)
				(type default)
			)
			(layer "B.Fab")
		)
		(fp_line
			(start 0.12065 -0.2794)
			(end -0.12065 -0.2794)
			(stroke
				(width 0.1)
				(type default)
			)
			(layer "B.Fab")
		)
		(fp_line
			(start -0.67945 -0.3048)
			(end -0.67945 0.3048)
			(stroke
				(width 0.1)
				(type default)
			)
			(layer "B.Fab")
		)
		(fp_line
			(start -0.12065 -0.3048)
			(end -0.67945 -0.3048)
			(stroke
				(width 0.1)
				(type default)
			)
			(layer "B.Fab")
		)
		(fp_line
			(start 0.12065 -0.305054)
			(end 0.12065 -0.2794)
			(stroke
				(width 0.1)
				(type default)
			)
			(layer "B.Fab")
		)
		(fp_line
			(start 0.67945 -0.305054)
			(end 0.12065 -0.305054)
			(stroke
				(width 0.1)
				(type default)
			)
			(layer "B.Fab")
		)
		(pad "1" smd circle
			(at 0.40005 0 90)
			(size 0 0)
			(layers "B.Cu" "B.Mask" "B.Paste")
			(net "P3V3_OCP_V3_2")
		)
		(pad "2" smd circle
			(at -0.40005 0 90)
			(size 0 0)
			(layers "B.Cu" "B.Mask" "B.Paste")
			(net "OCP_V3_2_ID0")
		)
	)
	(footprint ""
		(layer "B.Cu")
		(at 237.001812 -135.401558)
		(property "Reference" "R1019"
			(at 0 0 0)
			(layer "B.SilkS")
			(hide yes)
			(effects
				(font
					(size 1.27 1.27)
				)
				(justify mirror)
			)
		)
		(property "Value" ""
			(at 0 0 0)
			(layer "B.Fab")
			(effects
				(font
					(size 1.27 1.27)
				)
				(justify mirror)
			)
		)
		(duplicate_pad_numbers_are_jumpers no)
		(fp_line
			(start -0.7874 -0.4064)
			(end -0.7874 0.4064)
			(stroke
				(width 0.1524)
				(type default)
			)
			(layer "B.SilkS")
		)
		(fp_line
			(start -0.7874 0.4064)
			(end -0.344932 0.4064)
			(stroke
				(width 0.1524)
				(type default)
			)
			(layer "B.SilkS")
		)
		(fp_line
			(start 0.305308 0.4064)
			(end 0.7874 0.4064)
			(stroke
				(width 0.1524)
				(type default)
			)
			(layer "B.SilkS")
		)
		(fp_line
			(start 0.7874 -0.4064)
			(end -0.7874 -0.4064)
			(stroke
				(width 0.1524)
				(type default)
			)
			(layer "B.SilkS")
		)
		(fp_line
			(start 0.7874 -0.19177)
			(end 0.7874 -0.4064)
			(stroke
				(width 0.1524)
				(type default)
			)
			(layer "B.SilkS")
		)
		(fp_line
			(start 0.7874 0.4064)
			(end 0.7874 0.21971)
			(stroke
				(width 0.1524)
				(type default)
			)
			(layer "B.SilkS")
		)
		(fp_line
			(start -0.67945 -0.3048)
			(end -0.67945 0.3048)
			(stroke
				(width 0.1)
				(type default)
			)
			(layer "B.Fab")
		)
		(fp_line
			(start -0.67945 0.3048)
			(end -0.120396 0.3048)
			(stroke
				(width 0.1)
				(type default)
			)
			(layer "B.Fab")
		)
		(fp_line
			(start -0.12065 -0.3048)
			(end -0.67945 -0.3048)
			(stroke
				(width 0.1)
				(type default)
			)
			(layer "B.Fab")
		)
		(fp_line
			(start -0.12065 -0.2794)
			(end -0.12065 -0.3048)
			(stroke
				(width 0.1)
				(type default)
			)
			(layer "B.Fab")
		)
		(fp_line
			(start -0.120396 0.2794)
			(end 0.12065 0.2794)
			(stroke
				(width 0.1)
				(type default)
			)
			(layer "B.Fab")
		)
		(fp_line
			(start -0.120396 0.3048)
			(end -0.120396 0.2794)
			(stroke
				(width 0.1)
				(type default)
			)
			(layer "B.Fab")
		)
		(fp_line
			(start 0.12065 -0.305054)
			(end 0.12065 -0.2794)
			(stroke
				(width 0.1)
				(type default)
			)
			(layer "B.Fab")
		)
		(fp_line
			(start 0.12065 -0.2794)
			(end -0.12065 -0.2794)
			(stroke
				(width 0.1)
				(type default)
			)
			(layer "B.Fab")
		)
		(fp_line
			(start 0.12065 0.2794)
			(end 0.12065 0.3048)
			(stroke
				(width 0.1)
				(type default)
			)
			(layer "B.Fab")
		)
		(fp_line
			(start 0.12065 0.3048)
			(end 0.67945 0.3048)
			(stroke
				(width 0.1)
				(type default)
			)
			(layer "B.Fab")
		)
		(fp_line
			(start 0.67945 -0.305054)
			(end 0.12065 -0.305054)
			(stroke
				(width 0.1)
				(type default)
			)
			(layer "B.Fab")
		)
		(fp_line
			(start 0.67945 0.3048)
			(end 0.67945 -0.305054)
			(stroke
				(width 0.1)
				(type default)
			)
			(layer "B.Fab")
		)
		(pad "1" smd rect
			(at 0.40005 0)
			(size 0.4572 0.508)
			(layers "B.Cu" "B.Mask" "B.Paste")
			(net "CLK_25M_PCH_CPU1_DN")
		)
		(pad "2" smd rect
			(at -0.40005 0)
			(size 0.4572 0.508)
			(layers "B.Cu" "B.Mask" "B.Paste")
			(net "CLK_25M_NSSC_CPU1_DN")
		)
	)
	(footprint ""
		(layer "B.Cu")
		(at 325.193914 -62.004956 -90)
		(property "Reference" "R1675"
			(at 0 0 90)
			(layer "B.SilkS")
			(hide yes)
			(effects
				(font
					(size 1.27 1.27)
				)
				(justify mirror)
			)
		)
		(property "Value" ""
			(at 0 0 90)
			(layer "B.Fab")
			(effects
				(font
					(size 1.27 1.27)
				)
				(justify mirror)
			)
		)
		(duplicate_pad_numbers_are_jumpers no)
		(fp_line
			(start -0.7874 0.4064)
			(end 0.7874 0.4064)
			(stroke
				(width 0.1524)
				(type default)
			)
			(layer "B.SilkS")
		)
		(fp_line
			(start 0.7874 0.4064)
			(end 0.7874 -0.4064)
			(stroke
				(width 0.1524)
				(type default)
			)
			(layer "B.SilkS")
		)
		(fp_line
			(start -0.7874 -0.4064)
			(end -0.7874 0.4064)
			(stroke
				(width 0.1524)
				(type default)
			)
			(layer "B.SilkS")
		)
		(fp_line
			(start 0.7874 -0.4064)
			(end -0.7874 -0.4064)
			(stroke
				(width 0.1524)
				(type default)
			)
			(layer "B.SilkS")
		)
		(fp_line
			(start -0.67945 0.3048)
			(end -0.120396 0.3048)
			(stroke
				(width 0.1)
				(type default)
			)
			(layer "B.Fab")
		)
		(fp_line
			(start -0.120396 0.3048)
			(end -0.120396 0.2794)
			(stroke
				(width 0.1)
				(type default)
			)
			(layer "B.Fab")
		)
		(fp_line
			(start 0.12065 0.3048)
			(end 0.67945 0.3048)
			(stroke
				(width 0.1)
				(type default)
			)
			(layer "B.Fab")
		)
		(fp_line
			(start 0.67945 0.3048)
			(end 0.67945 -0.305054)
			(stroke
				(width 0.1)
				(type default)
			)
			(layer "B.Fab")
		)
		(fp_line
			(start -0.120396 0.2794)
			(end 0.12065 0.2794)
			(stroke
				(width 0.1)
				(type default)
			)
			(layer "B.Fab")
		)
		(fp_line
			(start 0.12065 0.2794)
			(end 0.12065 0.3048)
			(stroke
				(width 0.1)
				(type default)
			)
			(layer "B.Fab")
		)
		(fp_line
			(start -0.12065 -0.2794)
			(end -0.12065 -0.3048)
			(stroke
				(width 0.1)
				(type default)
			)
			(layer "B.Fab")
		)
		(fp_line
			(start 0.12065 -0.2794)
			(end -0.12065 -0.2794)
			(stroke
				(width 0.1)
				(type default)
			)
			(layer "B.Fab")
		)
		(fp_line
			(start -0.67945 -0.3048)
			(end -0.67945 0.3048)
			(stroke
				(width 0.1)
				(type default)
			)
			(layer "B.Fab")
		)
		(fp_line
			(start -0.12065 -0.3048)
			(end -0.67945 -0.3048)
			(stroke
				(width 0.1)
				(type default)
			)
			(layer "B.Fab")
		)
		(fp_line
			(start 0.12065 -0.305054)
			(end 0.12065 -0.2794)
			(stroke
				(width 0.1)
				(type default)
			)
			(layer "B.Fab")
		)
		(fp_line
			(start 0.67945 -0.305054)
			(end 0.12065 -0.305054)
			(stroke
				(width 0.1)
				(type default)
			)
			(layer "B.Fab")
		)
		(pad "1" smd circle
			(at 0.40005 0 90)
			(size 0 0)
			(layers "B.Cu" "B.Mask" "B.Paste")
			(net "FM_PCIE_EV_BIF_EN")
		)
		(pad "2" smd circle
			(at -0.40005 0 90)
			(size 0 0)
			(layers "B.Cu" "B.Mask" "B.Paste")
			(net "P3V3_AUX")
		)
	)
)
